(kicad_pcb
	(version 20260206)
	(generator "pcbnew")
	(generator_version "10.0")
	(general
		(thickness 1.21888)
		(legacy_teardrops no)
	)
	(paper "A4")
	(title_block
		(title "timecard-v8 — TimeCard-DC-V8_EXP.PcbDoc")
		(comment 1 "Time Appliance Project (Time Card) / footprints 120-132 of 288")
	)
	(layers
		(0 "F.Cu" signal "TOP")
		(4 "In1.Cu" signal "SGND")
		(6 "In2.Cu" signal "IN1")
		(8 "In3.Cu" signal "IN2")
		(10 "In4.Cu" signal "SGND1")
		(2 "B.Cu" signal "BOTTOM")
		(9 "F.Adhes" user "F.Adhesive")
		(11 "B.Adhes" user "B.Adhesive")
		(13 "F.Paste" user "Top Paste")
		(15 "B.Paste" user "Bottom Paste")
		(5 "F.SilkS" user "Top Overlay")
		(7 "B.SilkS" user "Bottom Overlay")
		(1 "F.Mask" user "Top Solder")
		(3 "B.Mask" user "Bottom Solder")
		(17 "Dwgs.User" user "User.Drawings")
		(19 "Cmts.User" user "User.Comments")
		(21 "Eco1.User" user "User.Eco1")
		(23 "Eco2.User" user "User.Eco2")
		(25 "Edge.Cuts" user)
		(27 "Margin" user)
		(31 "F.CrtYd" user "Top Courtyard")
		(29 "B.CrtYd" user "Bottom Courtyard")
		(35 "F.Fab" user "Top Component Center")
		(33 "B.Fab" user "Bottom Component Center")
	)
	(footprint "Vault:FP-C1005-050-0_05-IPC_A"
		(layer "F.Cu")
		(at 205.35952 129.4162 180)
		(property "Reference" "C70"
			(at -0.19518 -2.626931 0)
			(unlocked yes)
			(layer "F.SilkS")
			(effects
				(font
					(size 0.762 0.762)
					(thickness 0.2286)
				)
			)
		)
		(property "Value" "2.2uF_16V_0402"
			(at -2.744951 9.813815 90)
			(unlocked yes)
			(layer "F.SilkS")
			(hide yes)
			(effects
				(font
					(size 0.762 0.762)
					(thickness 0.2286)
				)
			)
		)
		(sheetname "POWER")
		(sheetfile "POWER.kicad_sch")
		(duplicate_pad_numbers_are_jumpers no)
		(fp_line
			(start 0.83623 0.73624)
			(end -0.83624 0.73624)
			(stroke
				(width 0.2)
				(type solid)
			)
			(layer "F.SilkS")
		)
		(fp_line
			(start 0.83623 -0.73624)
			(end -0.83624 -0.73624)
			(stroke
				(width 0.2)
				(type solid)
			)
			(layer "F.SilkS")
		)
		(fp_line
			(start 1.03623 0.53624)
			(end -1.03624 0.53624)
			(stroke
				(width 0.2)
				(type solid)
			)
			(layer "F.CrtYd")
		)
		(fp_line
			(start 1.03623 -0.53624)
			(end 1.03623 0.53624)
			(stroke
				(width 0.2)
				(type solid)
			)
			(layer "F.CrtYd")
		)
		(fp_line
			(start 1.03623 -0.53624)
			(end -1.03624 -0.53624)
			(stroke
				(width 0.2)
				(type solid)
			)
			(layer "F.CrtYd")
		)
		(fp_line
			(start -1.03624 -0.53624)
			(end -1.03624 0.53624)
			(stroke
				(width 0.2)
				(type solid)
			)
			(layer "F.CrtYd")
		)
		(fp_line
			(start 1.03623 0.53624)
			(end -1.03624 0.53624)
			(stroke
				(width 0.2)
				(type solid)
			)
			(layer "F.Fab")
		)
		(fp_line
			(start 1.03623 -0.53624)
			(end 1.03623 0.53624)
			(stroke
				(width 0.2)
				(type solid)
			)
			(layer "F.Fab")
		)
		(fp_line
			(start 1.03623 -0.53624)
			(end -1.03624 -0.53624)
			(stroke
				(width 0.2)
				(type solid)
			)
			(layer "F.Fab")
		)
		(fp_line
			(start 0.5 0)
			(end -0.5 0)
			(stroke
				(width 0.1)
				(type solid)
			)
			(layer "F.Fab")
		)
		(fp_line
			(start 0 -0.5)
			(end 0 0.5)
			(stroke
				(width 0.1)
				(type solid)
			)
			(layer "F.Fab")
		)
		(fp_line
			(start -1.03624 -0.53624)
			(end -1.03624 0.53624)
			(stroke
				(width 0.2)
				(type solid)
			)
			(layer "F.Fab")
		)
		(fp_text user "${REFERENCE}"
			(at -0.00001 0.09602 180)
			(unlocked yes)
			(layer "F.Fab")
			(effects
				(font
					(face "Arial")
					(size 0.63 0.63)
					(thickness 0.1)
				)
				(justify left bottom)
			)
		)
		(pad "1" smd rect
			(at -0.46658 0 180)
			(size 0.73933 0.67248)
			(layers "F.Cu" "F.Mask" "F.Paste")
			(net "P3V3_PVDD")
			(solder_mask_margin 0)
			(solder_paste_margin 0)
		)
		(pad "2" smd rect
			(at 0.46657 0 180)
			(size 0.73933 0.67248)
			(layers "F.Cu" "F.Mask" "F.Paste")
			(net "GND")
			(solder_mask_margin 0)
			(solder_paste_margin 0)
		)
	)
	(footprint "Vault:RESC1608X55X30NL15T15"
		(layer "F.Cu")
		(at 69.8761 55.6162 90)
		(property "Reference" "R35"
			(at -5.7714 0.026921 90)
			(unlocked yes)
			(layer "F.SilkS")
			(effects
				(font
					(size 0.762 0.762)
					(thickness 0.2286)
				)
			)
		)
		(property "Value" "200 OHM"
			(at -2.935471 4.78626 0)
			(unlocked yes)
			(layer "F.SilkS")
			(hide yes)
			(effects
				(font
					(size 0.762 0.762)
					(thickness 0.2286)
				)
			)
		)
		(sheetname "USER_IO_STATUS")
		(sheetfile "USER_IO_STATUS.kicad_sch")
		(duplicate_pad_numbers_are_jumpers no)
		(pad "1" smd rect
			(at -0.675 0 180)
			(size 0.95 0.8)
			(layers "F.Cu" "F.Mask" "F.Paste")
			(net "LED1")
		)
		(pad "2" smd rect
			(at 0.675 0 180)
			(size 0.95 0.8)
			(layers "F.Cu" "F.Mask" "F.Paste")
			(net "NetD3_1")
		)
	)
	(footprint "Vault:RESC1005X40X25NL05T05"
		(layer "F.Cu")
		(at 217.1261 80.8162)
		(property "Reference" "R101"
			(at 0.0286 -0.773069 0)
			(unlocked yes)
			(layer "F.SilkS")
			(effects
				(font
					(size 0.762 0.762)
					(thickness 0.2286)
				)
			)
		)
		(property "Value" "DNI_27_1%_0402"
			(at -2.732271 10.296375 270)
			(unlocked yes)
			(layer "F.SilkS")
			(hide yes)
			(effects
				(font
					(size 0.762 0.762)
					(thickness 0.2286)
				)
			)
		)
		(sheetname "USBUart_DipSelects")
		(sheetfile "USBUart_DipSelects.kicad_sch")
		(duplicate_pad_numbers_are_jumpers no)
		(pad "1" smd rect
			(at -0.45 0 90)
			(size 0.55 0.55)
			(layers "F.Cu" "F.Mask" "F.Paste")
			(net "FTDI_TX")
		)
		(pad "2" smd rect
			(at 0.45 0 90)
			(size 0.55 0.55)
			(layers "F.Cu" "F.Mask" "F.Paste")
			(net "UART1_RXD")
		)
	)
	(footprint "Passives:SOT65P210X110-3N"
		(layer "F.Cu")
		(at 229.6761 137.6412 -90)
		(property "Reference" "D7"
			(at -1.931655 0.45 0)
			(unlocked yes)
			(layer "F.SilkS")
			(effects
				(font
					(size 0.762 0.762)
					(thickness 0.2286)
				)
				(justify left bottom)
			)
		)
		(property "Value" "BAT54SW"
			(at 0.551455 -1.0501 0)
			(unlocked yes)
			(layer "F.SilkS")
			(hide yes)
			(effects
				(font
					(size 0.762 0.762)
					(thickness 0.2286)
				)
				(justify left bottom)
			)
		)
		(sheetname "PCIe_JTAG")
		(sheetfile "PCIe_JTAG.kicad_sch")
		(duplicate_pad_numbers_are_jumpers no)
		(fp_line
			(start 0.675 1.1)
			(end -0.32499 1.1)
			(stroke
				(width 0.2)
				(type solid)
			)
			(layer "F.SilkS")
		)
		(fp_line
			(start 0.675 1.1)
			(end 0.675 0.65)
			(stroke
				(width 0.2)
				(type solid)
			)
			(layer "F.SilkS")
		)
		(fp_line
			(start 0.675 -0.65)
			(end 0.675 -1.1)
			(stroke
				(width 0.2)
				(type solid)
			)
			(layer "F.SilkS")
		)
		(fp_line
			(start 0.675 -1.1)
			(end -0.32499 -1.1)
			(stroke
				(width 0.2)
				(type solid)
			)
			(layer "F.SilkS")
		)
		(fp_circle
			(center -1.125 -1.45)
			(end -1.25 -1.45)
			(stroke
				(width 0.25)
				(type solid)
			)
			(fill no)
			(layer "F.SilkS")
		)
		(pad "1" smd rect
			(at -1.125 -0.65)
			(size 0.5 0.9)
			(layers "F.Cu" "F.Mask" "F.Paste")
			(net "GND")
		)
		(pad "2" smd rect
			(at -1.125 0.65)
			(size 0.5 0.9)
			(layers "F.Cu" "F.Mask" "F.Paste")
			(net "+3.3V")
		)
		(pad "3" smd rect
			(at 1.125 0)
			(size 0.5 0.9)
			(layers "F.Cu" "F.Mask" "F.Paste")
			(net "FPGA_TMS")
		)
	)
	(footprint "Vault:RESC3216X89X64NL25T25"
		(layer "F.Cu")
		(at 225.5261 123.5162)
		(property "Reference" "R72"
			(at 3.1286 1.426931 0)
			(unlocked yes)
			(layer "F.SilkS")
			(effects
				(font
					(size 0.762 0.762)
					(thickness 0.2286)
				)
			)
		)
		(property "Value" "2mOhm_1%_1206"
			(at 7.62962 3.037071 0)
			(unlocked yes)
			(layer "F.SilkS")
			(hide yes)
			(effects
				(font
					(size 0.762 0.762)
					(thickness 0.2286)
				)
			)
		)
		(sheetname "POWER")
		(sheetfile "POWER.kicad_sch")
		(duplicate_pad_numbers_are_jumpers no)
		(fp_line
			(start -0.2 -0.825)
			(end 0.2 -0.825)
			(stroke
				(width 0.2)
				(type solid)
			)
			(layer "F.SilkS")
		)
		(fp_line
			(start -0.2 0.825)
			(end 0.2 0.825)
			(stroke
				(width 0.2)
				(type solid)
			)
			(layer "F.SilkS")
		)
		(pad "1" smd rect
			(at -1.325 0 90)
			(size 1.85 1.5)
			(layers "F.Cu" "F.Mask" "F.Paste")
			(net "P3V3_SENSE")
		)
		(pad "2" smd rect
			(at 1.325 0 90)
			(size 1.85 1.5)
			(layers "F.Cu" "F.Mask" "F.Paste")
			(net "+3.3V")
		)
	)
	(footprint "Vault:RESC1005X40X25LL05T05"
		(layer "F.Cu")
		(at 183.0261 84.8162 180)
		(property "Reference" "R53"
			(at 0.0714 1.073069 0)
			(unlocked yes)
			(layer "F.SilkS")
			(effects
				(font
					(size 0.762 0.762)
					(thickness 0.2286)
				)
			)
		)
		(property "Value" "4.7K_0402"
			(at -3.024391 2.374045 90)
			(unlocked yes)
			(layer "F.SilkS")
			(hide yes)
			(effects
				(font
					(size 0.762 0.762)
					(thickness 0.2286)
				)
			)
		)
		(sheetname "GPS_IMU_SENSORS")
		(sheetfile "GPS_IMU_SENSORS.kicad_sch")
		(duplicate_pad_numbers_are_jumpers no)
		(pad "1" smd rect
			(at -0.4 0 270)
			(size 0.45 0.45)
			(layers "F.Cu" "F.Mask" "F.Paste")
			(net "NetR53_1")
		)
		(pad "2" smd rect
			(at 0.4 0 270)
			(size 0.45 0.45)
			(layers "F.Cu" "F.Mask" "F.Paste")
			(net "+3.3V")
		)
	)
	(footprint "Vault:RESC1005X40X25LL05T05"
		(layer "F.Cu")
		(at 188.0261 82.8162 180)
		(property "Reference" "R55"
			(at 0.3714 1.673079 0)
			(unlocked yes)
			(layer "F.SilkS")
			(effects
				(font
					(size 0.762 0.762)
					(thickness 0.2286)
				)
			)
		)
		(property "Value" "4.7K_0402"
			(at -3.024391 2.374045 90)
			(unlocked yes)
			(layer "F.SilkS")
			(hide yes)
			(effects
				(font
					(size 0.762 0.762)
					(thickness 0.2286)
				)
			)
		)
		(sheetname "GPS_IMU_SENSORS")
		(sheetfile "GPS_IMU_SENSORS.kicad_sch")
		(duplicate_pad_numbers_are_jumpers no)
		(pad "1" smd rect
			(at -0.4 0 270)
			(size 0.45 0.45)
			(layers "F.Cu" "F.Mask" "F.Paste")
			(net "BNO_BLIND")
		)
		(pad "2" smd rect
			(at 0.4 0 270)
			(size 0.45 0.45)
			(layers "F.Cu" "F.Mask" "F.Paste")
			(net "NetR55_2")
		)
	)
	(footprint "Vault:RESC1005X40X25LL05T05"
		(layer "F.Cu")
		(at 236.4261 131.8162)
		(property "Reference" "R79"
			(at 2.4286 -0.173079 0)
			(unlocked yes)
			(layer "F.SilkS")
			(effects
				(font
					(size 0.762 0.762)
					(thickness 0.2286)
				)
			)
		)
		(property "Value" "0_1%_0402"
			(at -2.579881 6.66536 270)
			(unlocked yes)
			(layer "F.SilkS")
			(hide yes)
			(effects
				(font
					(size 0.762 0.762)
					(thickness 0.2286)
				)
			)
		)
		(sheetname "POWER")
		(sheetfile "POWER.kicad_sch")
		(duplicate_pad_numbers_are_jumpers no)
		(pad "1" smd rect
			(at -0.4 0 90)
			(size 0.45 0.45)
			(layers "F.Cu" "F.Mask" "F.Paste")
			(net "NetR79_1")
		)
		(pad "2" smd rect
			(at 0.4 0 90)
			(size 0.45 0.45)
			(layers "F.Cu" "F.Mask" "F.Paste")
			(net "GND")
		)
	)
	(footprint "Vault:FP-MK212BG-MFG"
		(layer "F.Cu")
		(at 216.9261 68.8162 180)
		(property "Reference" "C55"
			(at 0.2286 -1.873079 180)
			(unlocked yes)
			(layer "F.SilkS")
			(effects
				(font
					(size 0.762 0.762)
					(thickness 0.2286)
				)
			)
		)
		(property "Value" "10uF"
			(at -3.240271 2.22164 90)
			(unlocked yes)
			(layer "F.SilkS")
			(hide yes)
			(effects
				(font
					(size 0.762 0.762)
					(thickness 0.2286)
				)
			)
		)
		(sheetname "GPS_IMU_SENSORS")
		(sheetfile "GPS_IMU_SENSORS.kicad_sch")
		(duplicate_pad_numbers_are_jumpers no)
		(fp_line
			(start 0.125 0.725)
			(end -0.125 0.725)
			(stroke
				(width 0.2)
				(type solid)
			)
			(layer "F.SilkS")
		)
		(fp_line
			(start 0.125 -0.725)
			(end -0.125 -0.725)
			(stroke
				(width 0.2)
				(type solid)
			)
			(layer "F.SilkS")
		)
		(fp_line
			(start 1.6 0.825)
			(end -1.6 0.825)
			(stroke
				(width 0.2)
				(type solid)
			)
			(layer "F.CrtYd")
		)
		(fp_line
			(start 1.6 -0.825)
			(end 1.6 0.825)
			(stroke
				(width 0.2)
				(type solid)
			)
			(layer "F.CrtYd")
		)
		(fp_line
			(start 1.6 -0.825)
			(end -1.6 -0.825)
			(stroke
				(width 0.2)
				(type solid)
			)
			(layer "F.CrtYd")
		)
		(fp_line
			(start -1.6 -0.825)
			(end -1.6 0.825)
			(stroke
				(width 0.2)
				(type solid)
			)
			(layer "F.CrtYd")
		)
		(fp_line
			(start 1.6 0.825)
			(end -1.6 0.825)
			(stroke
				(width 0.2)
				(type solid)
			)
			(layer "F.Fab")
		)
		(fp_line
			(start 1.6 -0.825)
			(end 1.6 0.825)
			(stroke
				(width 0.2)
				(type solid)
			)
			(layer "F.Fab")
		)
		(fp_line
			(start 1.6 -0.825)
			(end -1.6 -0.825)
			(stroke
				(width 0.2)
				(type solid)
			)
			(layer "F.Fab")
		)
		(fp_line
			(start 0.5 0)
			(end -0.5 0)
			(stroke
				(width 0.1)
				(type solid)
			)
			(layer "F.Fab")
		)
		(fp_line
			(start 0 -0.5)
			(end 0 0.5)
			(stroke
				(width 0.1)
				(type solid)
			)
			(layer "F.Fab")
		)
		(fp_line
			(start -1.6 -0.825)
			(end -1.6 0.825)
			(stroke
				(width 0.2)
				(type solid)
			)
			(layer "F.Fab")
		)
		(fp_text user "${REFERENCE}"
			(at -0.00001 0.09602 180)
			(unlocked yes)
			(layer "F.Fab")
			(effects
				(font
					(face "Arial")
					(size 0.63 0.63)
					(thickness 0.1)
				)
				(justify left bottom)
			)
		)
		(pad "1" smd rect
			(at -1 0 180)
			(size 1 1.25)
			(layers "F.Cu" "F.Mask" "F.Paste")
			(net "+3.3V")
			(solder_mask_margin 0)
			(solder_paste_margin 0)
		)
		(pad "2" smd rect
			(at 1 0 180)
			(size 1 1.25)
			(layers "F.Cu" "F.Mask" "F.Paste")
			(net "GND")
			(solder_mask_margin 0)
			(solder_paste_margin 0)
		)
	)
	(footprint "SamacSys:SOP50P310X90-8N"
		(layer "F.Cu")
		(at 82.1261 136.1162 180)
		(property "Reference" "U16"
			(at 0.2286 2.026931 180)
			(unlocked yes)
			(layer "F.SilkS")
			(effects
				(font
					(size 0.762 0.762)
					(thickness 0.2286)
				)
			)
		)
		(property "Value" "NC7WV125K8X"
			(at 6.207715 2.884671 180)
			(unlocked yes)
			(layer "F.SilkS")
			(hide yes)
			(effects
				(font
					(size 0.762 0.762)
					(thickness 0.2286)
				)
			)
		)
		(sheetname "USER_IO")
		(sheetfile "USER_IO.kicad_sch")
		(duplicate_pad_numbers_are_jumpers no)
		(fp_line
			(start 0.8 1)
			(end -0.8 1)
			(stroke
				(width 0.2)
				(type solid)
			)
			(layer "F.SilkS")
		)
		(fp_line
			(start 0.8 -1)
			(end 0.8 1)
			(stroke
				(width 0.2)
				(type solid)
			)
			(layer "F.SilkS")
		)
		(fp_line
			(start 0.8 -1)
			(end -0.8 -1)
			(stroke
				(width 0.2)
				(type solid)
			)
			(layer "F.SilkS")
		)
		(fp_line
			(start -0.8 -1)
			(end -0.8 1)
			(stroke
				(width 0.2)
				(type solid)
			)
			(layer "F.SilkS")
		)
		(fp_line
			(start -1.15 -1.25)
			(end -2 -1.25)
			(stroke
				(width 0.2)
				(type solid)
			)
			(layer "F.SilkS")
		)
		(pad "1" smd rect
			(at -1.575 -0.75 180)
			(size 0.85 0.3)
			(layers "F.Cu" "F.Mask" "F.Paste")
			(net "ANT4_IO_OUT")
		)
		(pad "2" smd rect
			(at -1.575 -0.25 180)
			(size 0.85 0.3)
			(layers "F.Cu" "F.Mask" "F.Paste")
			(net "ANT4_OUT")
		)
		(pad "3" smd rect
			(at -1.575 0.25 180)
			(size 0.85 0.3)
			(layers "F.Cu" "F.Mask" "F.Paste")
			(net "ANT4_IN")
		)
		(pad "4" smd rect
			(at -1.575 0.75 180)
			(size 0.85 0.3)
			(layers "F.Cu" "F.Mask" "F.Paste")
			(net "GND")
		)
		(pad "5" smd rect
			(at 1.575 0.75 180)
			(size 0.85 0.3)
			(layers "F.Cu" "F.Mask" "F.Paste")
			(net "NetR34_1")
		)
		(pad "6" smd rect
			(at 1.575 0.25 180)
			(size 0.85 0.3)
			(layers "F.Cu" "F.Mask" "F.Paste")
			(net "NetR34_1")
		)
		(pad "7" smd rect
			(at 1.575 -0.25 180)
			(size 0.85 0.3)
			(layers "F.Cu" "F.Mask" "F.Paste")
			(net "ANT4_IO_IN")
		)
		(pad "8" smd rect
			(at 1.575 -0.75 180)
			(size 0.85 0.3)
			(layers "F.Cu" "F.Mask" "F.Paste")
			(net "+3.3V")
		)
	)
	(footprint "SamacSys:155124M173200"
		(layer "F.Cu")
		(at 58.4511 71.6662 90)
		(property "Reference" "D13"
			(at -4.7 -0.231655 90)
			(unlocked yes)
			(layer "F.SilkS")
			(effects
				(font
					(size 0.762 0.762)
					(thickness 0.2286)
				)
				(justify left bottom)
			)
		)
		(property "Value" "155124M173200"
			(at -4.043045 -0.5715 0)
			(unlocked yes)
			(layer "F.SilkS")
			(hide yes)
			(effects
				(font
					(size 0.762 0.762)
					(thickness 0.2286)
				)
				(justify left bottom)
			)
		)
		(sheetname "USER_IO_STATUS")
		(sheetfile "USER_IO_STATUS.kicad_sch")
		(duplicate_pad_numbers_are_jumpers no)
		(fp_line
			(start -0.8 0.5)
			(end 0.8 0.5)
			(stroke
				(width 0.1)
				(type solid)
			)
			(layer "F.SilkS")
		)
		(fp_arc
			(start -2 -0.1)
			(mid -1.95 -0.05)
			(end -2 0)
			(stroke
				(width 0.1)
				(type solid)
			)
			(layer "F.SilkS")
		)
		(fp_arc
			(start -2 0)
			(mid -2.05 -0.05)
			(end -2 -0.1)
			(stroke
				(width 0.1)
				(type solid)
			)
			(layer "F.SilkS")
		)
		(pad "1" smd rect
			(at -1.4 0 180)
			(size 0.9 0.6)
			(layers "F.Cu" "F.Mask" "F.Paste")
			(net "+3.3V")
		)
		(pad "2" smd rect
			(at -0.45 -0.325 90)
			(size 0.6 0.55)
			(layers "F.Cu" "F.Mask" "F.Paste")
			(net "NetD13_2")
		)
		(pad "3" smd rect
			(at 0.45 -0.325 90)
			(size 0.6 0.55)
			(layers "F.Cu" "F.Mask" "F.Paste")
			(net "NetD13_3")
		)
		(pad "4" smd rect
			(at 1.4 0 180)
			(size 0.9 0.6)
			(layers "F.Cu" "F.Mask" "F.Paste")
			(net "NetD13_4")
		)
	)
	(footprint "Vault:RESC1005X40X25NL05T05"
		(layer "F.Cu")
		(at 240.0261 66.9162 -90)
		(property "Reference" "R13"
			(at -0.0233 0.775031 270)
			(unlocked yes)
			(layer "F.SilkS")
			(effects
				(font
					(size 0.762 0.762)
					(thickness 0.2286)
				)
			)
		)
		(property "Value" "27_1%_0402"
			(at -2.884671 3.18659 180)
			(unlocked yes)
			(layer "F.SilkS")
			(hide yes)
			(effects
				(font
					(size 0.762 0.762)
					(thickness 0.2286)
				)
			)
		)
		(sheetname "USBUart_DipSelects")
		(sheetfile "USBUart_DipSelects.kicad_sch")
		(duplicate_pad_numbers_are_jumpers no)
		(pad "1" smd rect
			(at -0.45 0)
			(size 0.55 0.55)
			(layers "F.Cu" "F.Mask" "F.Paste")
			(net "NetR13_1")
		)
		(pad "2" smd rect
			(at 0.45 0)
			(size 0.55 0.55)
			(layers "F.Cu" "F.Mask" "F.Paste")
			(net "FTDI_TX")
		)
	)
	(footprint "Vault:RESC1005X40X25LL05T10"
		(layer "F.Cu")
		(at 174.4261 83.3162 180)
		(property "Reference" "R89"
			(at -0.3286 2.273079 0)
			(unlocked yes)
			(layer "F.SilkS")
			(effects
				(font
					(size 0.762 0.762)
					(thickness 0.2286)
				)
			)
		)
		(property "Value" "10K_1%_0402"
			(at -2.579871 8.061915 90)
			(unlocked yes)
			(layer "F.SilkS")
			(hide yes)
			(effects
				(font
					(size 0.762 0.762)
					(thickness 0.2286)
				)
			)
		)
		(sheetname "USBUart_DipSelects")
		(sheetfile "USBUart_DipSelects.kicad_sch")
		(duplicate_pad_numbers_are_jumpers no)
		(pad "1" smd rect
			(at -0.375 0 270)
			(size 0.45 0.5)
			(layers "F.Cu" "F.Mask" "F.Paste")
			(net "+3.3V")
		)
		(pad "2" smd rect
			(at 0.375 0 270)
			(size 0.45 0.5)
			(layers "F.Cu" "F.Mask" "F.Paste")
			(net "DIP_SW_PPS_SEL")
		)
	)
)
